(
  (version 16.5)
  (tool
    (creator "conceptHDL")
    (last "conceptHDL")
  )
  (library "mstr_symbols")
  (design "p3v3_stby"
    (lastIds
      (lastNetId 4)
    )
    (nets
      ("N1" "g" -1 -1 1 3)
      ("N2" "page1_g" -1 -1 0 )
      ("N4" "page1_p3v3_stby" -1 -1 0 )
      ("N3" "p3v3_stby" -1 -1 2 )
    )

    (alias
      ("N2" -1 -1 "N1" -1 -1)
      ("N4" -1 -1 "N2" -1 -1)
      ("N4" -1 -1 "N3" -1 -1)
    )

  )
)
